(kicad_pcb
	(version 20240108)
	(generator "pcbnew")
	(generator_version "8.0")
	(general
		(thickness 1.62)
		(legacy_teardrops no)
	)
	(paper "A4")
	(title_block
		(title "Jetson Orin Baseboard")
		(date "2025-03-12")
		(rev "1.3.4")
		(company "Antmicro Ltd")
		(comment 1 "www.antmicro.com")
		(comment 9 "footprints 385-388 of 677")
	)
	(layers
		(0 "F.Cu" signal)
		(1 "In1.Cu" signal)
		(2 "In2.Cu" signal)
		(3 "In3.Cu" signal)
		(4 "In4.Cu" jumper)
		(5 "In5.Cu" signal)
		(6 "In6.Cu" signal)
		(31 "B.Cu" signal)
		(32 "B.Adhes" user "B.Adhesive")
		(33 "F.Adhes" user "F.Adhesive")
		(34 "B.Paste" user)
		(35 "F.Paste" user)
		(36 "B.SilkS" user "B.Silkscreen")
		(37 "F.SilkS" user "F.Silkscreen")
		(38 "B.Mask" user)
		(39 "F.Mask" user)
		(40 "Dwgs.User" user "User.Drawings")
		(41 "Cmts.User" user "User.Comments")
		(42 "Eco1.User" user "User.Eco1")
		(43 "Eco2.User" user "User.Eco2")
		(44 "Edge.Cuts" user)
		(45 "Margin" user)
		(46 "B.CrtYd" user "B.Courtyard")
		(47 "F.CrtYd" user "F.Courtyard")
		(48 "B.Fab" user)
		(49 "F.Fab" user)
	)
	(footprint "antmicro-footprints:C_0402_1005Metric"
		(layer "B.Cu")
		(at 126.75 92.75)
		(descr "Capacitor SMD 0402")
		(tags "capacitor SMD 0402")
		(property "Reference" "C16"
			(at 1.1 -0.45 180)
			(layer "B.SilkS")
			(effects
				(font
					(size 0.7 0.7)
					(thickness 0.15)
				)
				(justify left bottom mirror)
			)
		)
		(property "Value" "C_220n_0402"
			(at 0 -1.4 180)
			(layer "B.Fab")
			(effects
				(font
					(size 0.7 0.7)
					(thickness 0.15)
				)
				(justify left bottom mirror)
			)
		)
		(property "Footprint" "antmicro-footprints:C_0402_1005Metric"
			(at 0 0 0)
			(layer "F.Fab")
			(hide yes)
			(effects
				(font
					(size 1.27 1.27)
					(thickness 0.15)
				)
			)
		)
		(property "Datasheet" "https://www.yageo.com/en/Chart/Download/pdf/CC0402KRX5R6BB224"
			(at 0 0 0)
			(layer "F.Fab")
			(hide yes)
			(effects
				(font
					(size 1.27 1.27)
					(thickness 0.15)
				)
			)
		)
		(property "Author" "Antmicro"
			(at 0 0 0)
			(layer "B.Fab")
			(hide yes)
			(effects
				(font
					(size 1 1)
					(thickness 0.15)
				)
				(justify mirror)
			)
		)
		(property "Dielectric" ""
			(at 0 0 0)
			(layer "B.Fab")
			(hide yes)
			(effects
				(font
					(size 1 1)
					(thickness 0.15)
				)
				(justify mirror)
			)
		)
		(property "License" "Apache-2.0"
			(at 0 0 0)
			(layer "B.Fab")
			(hide yes)
			(effects
				(font
					(size 1 1)
					(thickness 0.15)
				)
				(justify mirror)
			)
		)
		(property "MPN" "CC0402KRX5R6BB224"
			(at 0 0 0)
			(layer "B.Fab")
			(hide yes)
			(effects
				(font
					(size 1 1)
					(thickness 0.15)
				)
				(justify mirror)
			)
		)
		(property "Manufacturer" "YAGEO"
			(at 0 0 0)
			(layer "B.Fab")
			(hide yes)
			(effects
				(font
					(size 1 1)
					(thickness 0.15)
				)
				(justify mirror)
			)
		)
		(property "Val" "220n"
			(at 0 0 0)
			(layer "B.Fab")
			(hide yes)
			(effects
				(font
					(size 1 1)
					(thickness 0.15)
				)
				(justify mirror)
			)
		)
		(property "Voltage" ""
			(at 0 0 0)
			(layer "B.Fab")
			(hide yes)
			(effects
				(font
					(size 1 1)
					(thickness 0.15)
				)
				(justify mirror)
			)
		)
		(sheetname "M.2")
		(sheetfile "m-2.kicad_sch")
		(attr smd)
		(fp_rect
			(start -0.925 0.47)
			(end 0.925 -0.47)
			(stroke
				(width 0.05)
				(type default)
			)
			(fill none)
			(layer "B.CrtYd")
		)
		(fp_line
			(start -0.494 -0.248)
			(end 0.504 -0.248)
			(stroke
				(width 0.15)
				(type solid)
			)
			(layer "B.Fab")
		)
		(fp_line
			(start -0.494 0.25)
			(end -0.494 -0.248)
			(stroke
				(width 0.15)
				(type solid)
			)
			(layer "B.Fab")
		)
		(fp_line
			(start 0.504 -0.248)
			(end 0.504 0.25)
			(stroke
				(width 0.15)
				(type solid)
			)
			(layer "B.Fab")
		)
		(fp_line
			(start 0.504 0.25)
			(end -0.494 0.25)
			(stroke
				(width 0.15)
				(type solid)
			)
			(layer "B.Fab")
		)
		(fp_text user "${REFERENCE}"
			(at -0.932 -3.168 180)
			(layer "B.Fab")
			(hide yes)
			(effects
				(font
					(size 0.7 0.7)
					(thickness 0.15)
				)
				(justify left bottom mirror)
			)
		)
		(fp_text user "License: Apache-2.0"
			(at -0.932 -5.17 180)
			(layer "B.Fab")
			(hide yes)
			(effects
				(font
					(size 0.7 0.7)
					(thickness 0.15)
				)
				(justify left bottom mirror)
			)
		)
		(fp_text user "Author: Antmicro"
			(at -0.932 -4.17 180)
			(layer "B.Fab")
			(hide yes)
			(effects
				(font
					(size 0.7 0.7)
					(thickness 0.15)
				)
				(justify left bottom mirror)
			)
		)
		(pad "1" smd roundrect
			(at -0.48 0)
			(size 0.59 0.64)
			(layers "B.Cu" "B.Paste" "B.Mask")
			(roundrect_rratio 0.25)
			(net 94 "/M.2/C_PCIE0_TX3_P")
			(pintype "passive")
		)
		(pad "2" smd roundrect
			(at 0.48 0)
			(size 0.59 0.64)
			(layers "B.Cu" "B.Paste" "B.Mask")
			(roundrect_rratio 0.25)
			(net 448 "PCIE0_TX3_P")
			(pintype "passive")
		)
	)
	(footprint "antmicro-footprints:R_0402_1005Metric"
		(layer "B.Cu")
		(at 75 110.2 -90)
		(descr "Resistor SMD 0402")
		(tags "resistor SMD 0402")
		(property "Reference" "R97"
			(at 0.76 -2.4 90)
			(layer "B.SilkS")
			(effects
				(font
					(size 0.7 0.7)
					(thickness 0.15)
				)
				(justify left bottom mirror)
			)
		)
		(property "Value" "R_1k_0402"
			(at 0 -1.4 90)
			(layer "B.Fab")
			(effects
				(font
					(size 0.7 0.7)
					(thickness 0.15)
				)
				(justify left bottom mirror)
			)
		)
		(property "Footprint" "antmicro-footprints:R_0402_1005Metric"
			(at 0 0 -90)
			(layer "F.Fab")
			(hide yes)
			(effects
				(font
					(size 1.27 1.27)
					(thickness 0.15)
				)
			)
		)
		(property "Datasheet" "https://www.bourns.com/docs/product-datasheets/cr.pdf"
			(at 0 0 -90)
			(layer "F.Fab")
			(hide yes)
			(effects
				(font
					(size 1.27 1.27)
					(thickness 0.15)
				)
			)
		)
		(property "Author" "Antmicro"
			(at -35.2 185.2 0)
			(layer "B.Fab")
			(hide yes)
			(effects
				(font
					(size 1 1)
					(thickness 0.15)
				)
				(justify mirror)
			)
		)
		(property "License" "Apache-2.0"
			(at -35.2 185.2 0)
			(layer "B.Fab")
			(hide yes)
			(effects
				(font
					(size 1 1)
					(thickness 0.15)
				)
				(justify mirror)
			)
		)
		(property "MPN" "CR0402-FX-1001GLF"
			(at -35.2 185.2 0)
			(layer "B.Fab")
			(hide yes)
			(effects
				(font
					(size 1 1)
					(thickness 0.15)
				)
				(justify mirror)
			)
		)
		(property "Manufacturer" "Bourns"
			(at -35.2 185.2 0)
			(layer "B.Fab")
			(hide yes)
			(effects
				(font
					(size 1 1)
					(thickness 0.15)
				)
				(justify mirror)
			)
		)
		(property "Tolerance" "1%"
			(at -35.2 185.2 0)
			(layer "B.Fab")
			(hide yes)
			(effects
				(font
					(size 1 1)
					(thickness 0.15)
				)
				(justify mirror)
			)
		)
		(property "Val" "1k"
			(at -35.2 185.2 0)
			(layer "B.Fab")
			(hide yes)
			(effects
				(font
					(size 1 1)
					(thickness 0.15)
				)
				(justify mirror)
			)
		)
		(sheetname "USB Debug, DP")
		(sheetfile "usb.kicad_sch")
		(attr smd exclude_from_pos_files exclude_from_bom dnp)
		(fp_rect
			(start -0.925 0.47)
			(end 0.925 -0.47)
			(stroke
				(width 0.05)
				(type default)
			)
			(fill none)
			(layer "B.CrtYd")
		)
		(fp_rect
			(start -0.5 0.25)
			(end 0.5 -0.25)
			(stroke
				(width 0.15)
				(type solid)
			)
			(fill none)
			(layer "B.Fab")
		)
		(fp_text user "Author: Antmicro"
			(at -0.95 -4.169 90)
			(layer "B.Fab")
			(hide yes)
			(effects
				(font
					(size 0.7 0.7)
					(thickness 0.15)
				)
				(justify left bottom mirror)
			)
		)
		(fp_text user "${REFERENCE}"
			(at -0.95 -3.168 90)
			(layer "B.Fab")
			(hide yes)
			(effects
				(font
					(size 0.7 0.7)
					(thickness 0.15)
				)
				(justify left bottom mirror)
			)
		)
		(fp_text user "License: Apache-2.0"
			(at -0.95 -5.169 90)
			(layer "B.Fab")
			(hide yes)
			(effects
				(font
					(size 0.7 0.7)
					(thickness 0.15)
				)
				(justify left bottom mirror)
			)
		)
		(pad "1" smd roundrect
			(at -0.48 0 270)
			(size 0.59 0.64)
			(layers "B.Cu" "B.Paste" "B.Mask")
			(roundrect_rratio 0.25)
			(net 310 "/USB Debug, DP/USBC0_EQ1")
			(pintype "passive")
		)
		(pad "2" smd roundrect
			(at 0.48 0 270)
			(size 0.59 0.64)
			(layers "B.Cu" "B.Paste" "B.Mask")
			(roundrect_rratio 0.25)
			(net 87 "+3V3")
			(pintype "passive")
		)
	)
	(footprint "antmicro-footprints:R_0402_1005Metric"
		(layer "B.Cu")
		(at 62.17 98.16 -90)
		(descr "Resistor SMD 0402")
		(tags "resistor SMD 0402")
		(property "Reference" "R244"
			(at 0.89 -0.3 90)
			(layer "B.SilkS")
			(effects
				(font
					(size 0.7 0.7)
					(thickness 0.15)
				)
				(justify left bottom mirror)
			)
		)
		(property "Value" "R_0R_0402"
			(at 0 -1.4 90)
			(layer "B.Fab")
			(effects
				(font
					(size 0.7 0.7)
					(thickness 0.15)
				)
				(justify left bottom mirror)
			)
		)
		(property "Footprint" "antmicro-footprints:R_0402_1005Metric"
			(at 0 0 -90)
			(layer "F.Fab")
			(hide yes)
			(effects
				(font
					(size 1.27 1.27)
					(thickness 0.15)
				)
			)
		)
		(property "Datasheet" "https://industrial.panasonic.com/cdbs/www-data/pdf/RDA0000/AOA0000C301.pdf"
			(at 0 0 -90)
			(layer "F.Fab")
			(hide yes)
			(effects
				(font
					(size 1.27 1.27)
					(thickness 0.15)
				)
			)
		)
		(property "Author" "Antmicro"
			(at -35.99 160.33 0)
			(layer "B.Fab")
			(hide yes)
			(effects
				(font
					(size 1 1)
					(thickness 0.15)
				)
				(justify mirror)
			)
		)
		(property "Current" "1A"
			(at -35.99 160.33 0)
			(layer "B.Fab")
			(hide yes)
			(effects
				(font
					(size 1 1)
					(thickness 0.15)
				)
				(justify mirror)
			)
		)
		(property "License" "Apache-2.0"
			(at -35.99 160.33 0)
			(layer "B.Fab")
			(hide yes)
			(effects
				(font
					(size 1 1)
					(thickness 0.15)
				)
				(justify mirror)
			)
		)
		(property "MPN" "ERJ2GE0R00X"
			(at -35.99 160.33 0)
			(layer "B.Fab")
			(hide yes)
			(effects
				(font
					(size 1 1)
					(thickness 0.15)
				)
				(justify mirror)
			)
		)
		(property "Manufacturer" "Panasonic"
			(at -35.99 160.33 0)
			(layer "B.Fab")
			(hide yes)
			(effects
				(font
					(size 1 1)
					(thickness 0.15)
				)
				(justify mirror)
			)
		)
		(property "Tolerance" ""
			(at -35.99 160.33 0)
			(layer "B.Fab")
			(hide yes)
			(effects
				(font
					(size 1 1)
					(thickness 0.15)
				)
				(justify mirror)
			)
		)
		(property "Val" "0R"
			(at -35.99 160.33 0)
			(layer "B.Fab")
			(hide yes)
			(effects
				(font
					(size 1 1)
					(thickness 0.15)
				)
				(justify mirror)
			)
		)
		(sheetname "USB Debug, DP")
		(sheetfile "usb.kicad_sch")
		(attr smd exclude_from_pos_files exclude_from_bom dnp)
		(fp_rect
			(start -0.925 0.47)
			(end 0.925 -0.47)
			(stroke
				(width 0.05)
				(type default)
			)
			(fill none)
			(layer "B.CrtYd")
		)
		(fp_rect
			(start -0.5 0.25)
			(end 0.5 -0.25)
			(stroke
				(width 0.15)
				(type solid)
			)
			(fill none)
			(layer "B.Fab")
		)
		(fp_text user "${REFERENCE}"
			(at -0.95 -3.168 90)
			(layer "B.Fab")
			(hide yes)
			(effects
				(font
					(size 0.7 0.7)
					(thickness 0.15)
				)
				(justify left bottom mirror)
			)
		)
		(fp_text user "Author: Antmicro"
			(at -0.95 -4.169 90)
			(layer "B.Fab")
			(hide yes)
			(effects
				(font
					(size 0.7 0.7)
					(thickness 0.15)
				)
				(justify left bottom mirror)
			)
		)
		(fp_text user "License: Apache-2.0"
			(at -0.95 -5.169 90)
			(layer "B.Fab")
			(hide yes)
			(effects
				(font
					(size 0.7 0.7)
					(thickness 0.15)
				)
				(justify left bottom mirror)
			)
		)
		(pad "1" smd roundrect
			(at -0.48 0 270)
			(size 0.59 0.64)
			(layers "B.Cu" "B.Paste" "B.Mask")
			(roundrect_rratio 0.25)
			(net 714 "GPIO010")
			(pintype "passive")
		)
		(pad "2" smd roundrect
			(at 0.48 0 270)
			(size 0.59 0.64)
			(layers "B.Cu" "B.Paste" "B.Mask")
			(roundrect_rratio 0.25)
			(net 713 "/USB Debug, DP/PDC_I2C1_IRQn")
			(pintype "passive")
		)
	)
	(footprint "antmicro-footprints:LED_0603_1608Metric_G"
		(layer "B.Cu")
		(at 108.4 70.3 180)
		(descr "LED SMD 0603 Green")
		(tags "LED SMD 0603 Green")
		(property "Reference" "D24"
			(at 1.1 -0.45 0)
			(layer "B.SilkS")
			(effects
				(font
					(size 0.7 0.7)
					(thickness 0.15)
				)
				(justify left bottom mirror)
			)
		)
		(property "Value" "LED_G_0603_LTST-C190GKT"
			(at -0.001 -1.599 0)
			(layer "B.Fab")
			(effects
				(font
					(size 0.7 0.7)
					(thickness 0.15)
				)
				(justify left bottom mirror)
			)
		)
		(property "Footprint" "antmicro-footprints:LED_0603_1608Metric_G"
			(at 0 0 180)
			(layer "F.Fab")
			(hide yes)
			(effects
				(font
					(size 1.27 1.27)
					(thickness 0.15)
				)
			)
		)
		(property "Datasheet" "https://media.digikey.com/pdf/Data%20Sheets/Lite-On%20PDFs/LTST-C190GKT.pdf"
			(at 0 0 180)
			(layer "F.Fab")
			(hide yes)
			(effects
				(font
					(size 1.27 1.27)
					(thickness 0.15)
				)
			)
		)
		(property "Author" "Antmicro"
			(at 216.8 140.6 0)
			(layer "B.Fab")
			(hide yes)
			(effects
				(font
					(size 1 1)
					(thickness 0.15)
				)
				(justify mirror)
			)
		)
		(property "Color" "Green"
			(at 216.8 140.6 0)
			(layer "B.Fab")
			(hide yes)
			(effects
				(font
					(size 1 1)
					(thickness 0.15)
				)
				(justify mirror)
			)
		)
		(property "License" "Apache-2.0"
			(at 216.8 140.6 0)
			(layer "B.Fab")
			(hide yes)
			(effects
				(font
					(size 1 1)
					(thickness 0.15)
				)
				(justify mirror)
			)
		)
		(property "MPN" "LTST-C190GKT"
			(at 216.8 140.6 0)
			(layer "B.Fab")
			(hide yes)
			(effects
				(font
					(size 1 1)
					(thickness 0.15)
				)
				(justify mirror)
			)
		)
		(property "Manufacturer" "Lite-On"
			(at 216.8 140.6 0)
			(layer "B.Fab")
			(hide yes)
			(effects
				(font
					(size 1 1)
					(thickness 0.15)
				)
				(justify mirror)
			)
		)
		(sheetname "CSI")
		(sheetfile "csi.kicad_sch")
		(attr smd)
		(fp_line
			(start 0.24 -0.001)
			(end 0.105328 -0.001008)
			(stroke
				(width 0.1)
				(type solid)
			)
			(layer "B.SilkS")
		)
		(fp_line
			(start 0.105328 0.198992)
			(end 0.105328 -0.201008)
			(stroke
				(width 0.1)
				(type solid)
			)
			(layer "B.SilkS")
		)
		(fp_line
			(start 0.105328 0.198992)
			(end -0.094672 -0.001008)
			(stroke
				(width 0.1)
				(type solid)
			)
			(layer "B.SilkS")
		)
		(fp_line
			(start -0.094672 0.198992)
			(end -0.094672 -0.201008)
			(stroke
				(width 0.1)
				(type solid)
			)
			(layer "B.SilkS")
		)
		(fp_line
			(start -0.094672 -0.001008)
			(end 0.105328 -0.201008)
			(stroke
				(width 0.1)
				(type solid)
			)
			(layer "B.SilkS")
		)
		(fp_line
			(start -0.22 0.35)
			(end 0.22 0.35)
			(stroke
				(width 0.15)
				(type solid)
			)
			(layer "B.SilkS")
		)
		(fp_line
			(start -0.22 -0.35)
			(end 0.22 -0.35)
			(stroke
				(width 0.15)
				(type solid)
			)
			(layer "B.SilkS")
		)
		(fp_line
			(start -0.24 -0.001008)
			(end -0.094672 -0.001008)
			(stroke
				(width 0.1)
				(type solid)
			)
			(layer "B.SilkS")
		)
		(fp_line
			(start -1.18 -0.321)
			(end -1.18 0.319)
			(stroke
				(width 0.15)
				(type solid)
			)
			(layer "B.SilkS")
		)
		(fp_rect
			(start 1.25 -0.65)
			(end -1.25 0.65)
			(stroke
				(width 0.05)
				(type solid)
			)
			(fill none)
			(layer "B.CrtYd")
		)
		(fp_line
			(start 0.201 0.202)
			(end 0.201 0)
			(stroke
				(width 0.15)
				(type solid)
			)
			(layer "B.Fab")
		)
		(fp_line
			(start 0.201 0)
			(end 0.599 0)
			(stroke
				(width 0.15)
				(type solid)
			)
			(layer "B.Fab")
		)
		(fp_line
			(start 0.201 0)
			(end 0.201 -0.2)
			(stroke
				(width 0.15)
				(type solid)
			)
			(layer "B.Fab")
		)
		(fp_line
			(start 0.201 -0.2)
			(end -0.101 0)
			(stroke
				(width 0.15)
				(type solid)
			)
			(layer "B.Fab")
		)
		(fp_line
			(start -0.101 0)
			(end 0.201 0.202)
			(stroke
				(width 0.15)
				(type solid)
			)
			(layer "B.Fab")
		)
		(fp_line
			(start -0.199 -0.1)
			(end -0.199 0.202)
			(stroke
				(width 0.15)
				(type solid)
			)
			(layer "B.Fab")
		)
		(fp_line
			(start -0.199 -0.1)
			(end -0.199 -0.2)
			(stroke
				(width 0.15)
				(type solid)
			)
			(layer "B.Fab")
		)
		(fp_line
			(start -0.597 0)
			(end -0.199 0)
			(stroke
				(width 0.15)
				(type solid)
			)
			(layer "B.Fab")
		)
		(fp_rect
			(start 0.848 -0.4)
			(end -0.85 0.402)
			(stroke
				(width 0.15)
				(type solid)
			)
			(fill none)
			(layer "B.Fab")
		)
		(fp_text user "License: Apache-2.0"
			(at -1.4224 -3.599 0)
			(layer "B.Fab")
			(hide yes)
			(effects
				(font
					(size 0.7 0.7)
					(thickness 0.15)
				)
				(justify left bottom mirror)
			)
		)
		(fp_text user "${REFERENCE}"
			(at -1.4224 -5.999 0)
			(layer "B.Fab")
			(hide yes)
			(effects
				(font
					(size 0.7 0.7)
					(thickness 0.15)
				)
				(justify left bottom mirror)
			)
		)
		(fp_text user "Author: Antmicro"
			(at -1.4224 -4.799 0)
			(layer "B.Fab")
			(hide yes)
			(effects
				(font
					(size 0.7 0.7)
					(thickness 0.15)
				)
				(justify left bottom mirror)
			)
		)
		(pad "1" smd roundrect
			(at -0.7 0)
			(size 0.8 1)
			(layers "B.Cu" "B.Paste" "B.Mask")
			(roundrect_rratio 0.2)
			(net 1 "GND")
			(pinfunction "C")
			(pintype "passive")
		)
		(pad "2" smd roundrect
			(at 0.7 0)
			(size 0.8 1)
			(layers "B.Cu" "B.Paste" "B.Mask")
			(roundrect_rratio 0.2)
			(net 161 "Net-(D24-A)")
			(pinfunction "A")
			(pintype "passive")
		)
	)
)
